(kicad_pcb
	(version 20260206)
	(generator "pcbnew")
	(generator_version "10.0")
	(general
		(thickness 1.6)
		(legacy_teardrops no)
	)
	(paper "A4")
	(title_block
		(title "4HDD Backplane_Layout.brd")
		(comment 1 "Tioga Pass / footprints 43-49 of 97")
	)
	(layers
		(0 "F.Cu" signal "TOP")
		(4 "In1.Cu" signal "L2GND")
		(6 "In2.Cu" signal "L3")
		(8 "In3.Cu" signal "L4")
		(10 "In4.Cu" signal "L5GND")
		(2 "B.Cu" signal "BOTTOM")
		(9 "F.Adhes" user "F.Adhesive")
		(11 "B.Adhes" user "B.Adhesive")
		(13 "F.Paste" user "Package Geometry/Pastemask Top")
		(15 "B.Paste" user "Package Geometry/Pastemask Bottom")
		(5 "F.SilkS" user "Ref Des/Silkscreen Top")
		(7 "B.SilkS" user "Ref Des/Silkscreen Bottom")
		(1 "F.Mask" user "Board Geometry/Soldermask Top")
		(3 "B.Mask" user "Board Geometry/Soldermask Bottom")
		(17 "Dwgs.User" user "User.Drawings")
		(19 "Cmts.User" user "User.Comments")
		(21 "Eco1.User" user "User.Eco1")
		(23 "Eco2.User" user "User.Eco2")
		(25 "Edge.Cuts" user "Board Geometry/Outline")
		(27 "Margin" user)
		(31 "F.CrtYd" user "Package Geometry/Place Bound Top")
		(29 "B.CrtYd" user "Package Geometry/Place Bound Bottom")
		(35 "F.Fab" user "Ref Des/Assembly Top")
		(33 "B.Fab" user "Ref Des/Assembly Bottom")
	)
	(footprint ""
		(layer "F.Cu")
		(at 82.403442 -11.334496 180)
		(property "Reference" "C32"
			(at 0 0 180)
			(layer "F.SilkS")
			(hide yes)
			(effects
				(font
					(size 1.27 1.27)
				)
			)
		)
		(property "Value" "SCD1U16V2JX-1-GP"
			(at 1.1811 -2.7051 180)
			(unlocked yes)
			(layer "F.Fab")
			(hide yes)
			(effects
				(font
					(size 1.016 1.016)
					(thickness 0.1524)
				)
			)
		)
		(property "Device Type" "C402H22"
			(at 1.1811 -4.2291 180)
			(unlocked yes)
			(layer "F.Fab")
			(hide yes)
			(effects
				(font
					(size 1.016 1.016)
					(thickness 0.1524)
				)
			)
		)
		(duplicate_pad_numbers_are_jumpers no)
		(fp_rect
			(start -0.4318 0.9525)
			(end 0.4318 -0.9525)
			(stroke
				(width 0)
				(type default)
			)
			(fill no)
			(layer "F.CrtYd")
		)
		(fp_rect
			(start -0.4318 0.9525)
			(end 0.4318 -0.9525)
			(stroke
				(width 0)
				(type default)
			)
			(fill no)
			(layer "F.Fab")
		)
		(pad "1" smd custom
			(at 0 -0.4445 180)
			(size 0.1524 0.1524)
			(layers "F.Cu" "F.Mask" "F.Paste")
			(net "P3V3")
			(options
				(clearance outline)
				(anchor circle)
			)
			(primitives
				(gr_poly
					(pts
						(arc
							(start 0.3048 -0.2032)
							(mid 0.275042 -0.275042)
							(end 0.2032 -0.3048)
						)
						(arc
							(start -0.2032 -0.3048)
							(mid -0.275042 -0.275042)
							(end -0.3048 -0.2032)
						)
						(arc
							(start -0.3048 0.2032)
							(mid -0.275042 0.275042)
							(end -0.2032 0.3048)
						)
						(arc
							(start 0.2032 0.3048)
							(mid 0.275042 0.275042)
							(end 0.3048 0.2032)
						)
					)
					(width 0)
					(fill yes)
				)
			)
		)
		(pad "2" smd custom
			(at 0 0.4445 180)
			(size 0.1524 0.1524)
			(layers "F.Cu" "F.Mask" "F.Paste")
			(net "GND")
			(options
				(clearance outline)
				(anchor circle)
			)
			(primitives
				(gr_poly
					(pts
						(arc
							(start 0.3048 -0.2032)
							(mid 0.275042 -0.275042)
							(end 0.2032 -0.3048)
						)
						(arc
							(start -0.2032 -0.3048)
							(mid -0.275042 -0.275042)
							(end -0.3048 -0.2032)
						)
						(arc
							(start -0.3048 0.2032)
							(mid -0.275042 0.275042)
							(end -0.2032 0.3048)
						)
						(arc
							(start 0.2032 0.3048)
							(mid 0.275042 0.275042)
							(end 0.3048 0.2032)
						)
					)
					(width 0)
					(fill yes)
				)
			)
		)
	)
	(footprint ""
		(layer "F.Cu")
		(at 77.724 -53.213 -90)
		(property "Reference" "C4"
			(at 0 0 270)
			(layer "F.SilkS")
			(hide yes)
			(effects
				(font
					(size 1.27 1.27)
				)
			)
		)
		(property "Value" "SCD1U25V2KX-GP"
			(at 1.1811 -2.7051 270)
			(unlocked yes)
			(layer "F.Fab")
			(hide yes)
			(effects
				(font
					(size 1.016 1.016)
					(thickness 0.1524)
				)
			)
		)
		(property "Device Type" "C402H22"
			(at 1.1811 -4.2291 270)
			(unlocked yes)
			(layer "F.Fab")
			(hide yes)
			(effects
				(font
					(size 1.016 1.016)
					(thickness 0.1524)
				)
			)
		)
		(duplicate_pad_numbers_are_jumpers no)
		(fp_rect
			(start -0.4318 0.9525)
			(end 0.4318 -0.9525)
			(stroke
				(width 0)
				(type default)
			)
			(fill no)
			(layer "F.CrtYd")
		)
		(fp_rect
			(start -0.4318 0.9525)
			(end 0.4318 -0.9525)
			(stroke
				(width 0)
				(type default)
			)
			(fill no)
			(layer "F.Fab")
		)
		(pad "1" smd custom
			(at 0 -0.4445 270)
			(size 0.1524 0.1524)
			(layers "F.Cu" "F.Mask" "F.Paste")
			(net "P5V_SW_R")
			(options
				(clearance outline)
				(anchor circle)
			)
			(primitives
				(gr_poly
					(pts
						(arc
							(start 0.3048 -0.2032)
							(mid 0.275042 -0.275042)
							(end 0.2032 -0.3048)
						)
						(arc
							(start -0.2032 -0.3048)
							(mid -0.275042 -0.275042)
							(end -0.3048 -0.2032)
						)
						(arc
							(start -0.3048 0.2032)
							(mid -0.275042 0.275042)
							(end -0.2032 0.3048)
						)
						(arc
							(start 0.2032 0.3048)
							(mid 0.275042 0.275042)
							(end 0.3048 0.2032)
						)
					)
					(width 0)
					(fill yes)
				)
			)
		)
		(pad "2" smd custom
			(at 0 0.4445 270)
			(size 0.1524 0.1524)
			(layers "F.Cu" "F.Mask" "F.Paste")
			(net "GND")
			(options
				(clearance outline)
				(anchor circle)
			)
			(primitives
				(gr_poly
					(pts
						(arc
							(start 0.3048 -0.2032)
							(mid 0.275042 -0.275042)
							(end 0.2032 -0.3048)
						)
						(arc
							(start -0.2032 -0.3048)
							(mid -0.275042 -0.275042)
							(end -0.3048 -0.2032)
						)
						(arc
							(start -0.3048 0.2032)
							(mid -0.275042 0.275042)
							(end -0.2032 0.3048)
						)
						(arc
							(start 0.2032 0.3048)
							(mid 0.275042 0.275042)
							(end 0.3048 0.2032)
						)
					)
					(width 0)
					(fill yes)
				)
			)
		)
	)
	(footprint ""
		(layer "F.Cu")
		(at 91.694 -10.033)
		(property "Reference" "C31"
			(at 0 0 0)
			(layer "F.SilkS")
			(hide yes)
			(effects
				(font
					(size 1.27 1.27)
				)
			)
		)
		(property "Value" "SCD1U25V2KX-2-GP"
			(at 1.1811 -2.7051 0)
			(unlocked yes)
			(layer "F.Fab")
			(hide yes)
			(effects
				(font
					(size 1.016 1.016)
					(thickness 0.1524)
				)
			)
		)
		(property "Device Type" "C402H22"
			(at 1.1811 -4.2291 0)
			(unlocked yes)
			(layer "F.Fab")
			(hide yes)
			(effects
				(font
					(size 1.016 1.016)
					(thickness 0.1524)
				)
			)
		)
		(duplicate_pad_numbers_are_jumpers no)
		(fp_rect
			(start -0.4318 0.9525)
			(end 0.4318 -0.9525)
			(stroke
				(width 0)
				(type default)
			)
			(fill no)
			(layer "F.CrtYd")
		)
		(fp_rect
			(start -0.4318 0.9525)
			(end 0.4318 -0.9525)
			(stroke
				(width 0)
				(type default)
			)
			(fill no)
			(layer "F.Fab")
		)
		(pad "1" smd custom
			(at 0 -0.4445)
			(size 0.1524 0.1524)
			(layers "F.Cu" "F.Mask" "F.Paste")
			(net "P12V")
			(options
				(clearance outline)
				(anchor circle)
			)
			(primitives
				(gr_poly
					(pts
						(arc
							(start 0.3048 -0.2032)
							(mid 0.275042 -0.275042)
							(end 0.2032 -0.3048)
						)
						(arc
							(start -0.2032 -0.3048)
							(mid -0.275042 -0.275042)
							(end -0.3048 -0.2032)
						)
						(arc
							(start -0.3048 0.2032)
							(mid -0.275042 0.275042)
							(end -0.2032 0.3048)
						)
						(arc
							(start 0.2032 0.3048)
							(mid 0.275042 0.275042)
							(end 0.3048 0.2032)
						)
					)
					(width 0)
					(fill yes)
				)
			)
		)
		(pad "2" smd custom
			(at 0 0.4445)
			(size 0.1524 0.1524)
			(layers "F.Cu" "F.Mask" "F.Paste")
			(net "SW_SW_L_N_0")
			(options
				(clearance outline)
				(anchor circle)
			)
			(primitives
				(gr_poly
					(pts
						(arc
							(start 0.3048 -0.2032)
							(mid 0.275042 -0.275042)
							(end 0.2032 -0.3048)
						)
						(arc
							(start -0.2032 -0.3048)
							(mid -0.275042 -0.275042)
							(end -0.3048 -0.2032)
						)
						(arc
							(start -0.3048 0.2032)
							(mid -0.275042 0.275042)
							(end -0.2032 0.3048)
						)
						(arc
							(start 0.2032 0.3048)
							(mid 0.275042 0.275042)
							(end 0.3048 0.2032)
						)
					)
					(width 0)
					(fill yes)
				)
			)
		)
	)
	(footprint ""
		(layer "F.Cu")
		(at 83.435444 -41.18102 -90)
		(property "Reference" "R161"
			(at 0 0 270)
			(layer "F.SilkS")
			(hide yes)
			(effects
				(font
					(size 1.27 1.27)
				)
			)
		)
		(property "Value" "0R5J-5-GP"
			(at 0 -8.9535 270)
			(unlocked yes)
			(layer "F.Fab")
			(hide yes)
			(effects
				(font
					(size 1.27 1.016)
					(thickness 0.1524)
				)
			)
		)
		(property "Device Type" "R805H24"
			(at 0 -10.6299 270)
			(unlocked yes)
			(layer "F.Fab")
			(hide yes)
			(effects
				(font
					(size 1.27 1.016)
					(thickness 0.1524)
				)
			)
		)
		(duplicate_pad_numbers_are_jumpers no)
		(fp_line
			(start -0.889 1.7018)
			(end 0.889 1.7018)
			(stroke
				(width 0.1524)
				(type default)
			)
			(layer "F.SilkS")
		)
		(fp_line
			(start 0.889 1.7018)
			(end 0.889 -0.508)
			(stroke
				(width 0.1524)
				(type default)
			)
			(layer "F.SilkS")
		)
		(fp_line
			(start -0.889 0.0762)
			(end -0.889 1.7018)
			(stroke
				(width 0.1524)
				(type default)
			)
			(layer "F.SilkS")
		)
		(fp_line
			(start -0.889 -1.7018)
			(end -0.889 0.2794)
			(stroke
				(width 0.1524)
				(type default)
			)
			(layer "F.SilkS")
		)
		(fp_line
			(start 0.889 -1.7018)
			(end 0.889 -0.381)
			(stroke
				(width 0.1524)
				(type default)
			)
			(layer "F.SilkS")
		)
		(fp_line
			(start 0.889 -1.7018)
			(end -0.889 -1.7018)
			(stroke
				(width 0.1524)
				(type default)
			)
			(layer "F.SilkS")
		)
		(fp_poly
			(pts
				(xy 0.9652 -1.778) (xy 0.9652 1.778) (xy -0.9652 1.778) (xy -0.9652 -1.778)
			)
			(stroke
				(width 0)
				(type default)
			)
			(fill no)
			(layer "F.CrtYd")
		)
		(fp_rect
			(start -0.9652 1.778)
			(end 0.9652 -1.778)
			(stroke
				(width 0)
				(type default)
			)
			(fill no)
			(layer "F.Fab")
		)
		(pad "1" smd rect
			(at 0 -0.9652 270)
			(size 1.397 1.143)
			(layers "F.Cu" "F.Mask" "F.Paste")
			(net "P12V")
		)
		(pad "2" smd rect
			(at 0 0.9652 270)
			(size 1.397 1.143)
			(layers "F.Cu" "F.Mask" "F.Paste")
			(net "P12V_SW_R")
		)
	)
	(footprint ""
		(layer "F.Cu")
		(at 74.9046 -41.8592 -90)
		(property "Reference" "C10"
			(at 0 0 270)
			(layer "F.SilkS")
			(hide yes)
			(effects
				(font
					(size 1.27 1.27)
				)
			)
		)
		(property "Value" "SCD1U25V2KX-GP"
			(at 1.1811 -2.7051 270)
			(unlocked yes)
			(layer "F.Fab")
			(hide yes)
			(effects
				(font
					(size 1.016 1.016)
					(thickness 0.1524)
				)
			)
		)
		(property "Device Type" "C402H22"
			(at 1.1811 -4.2291 270)
			(unlocked yes)
			(layer "F.Fab")
			(hide yes)
			(effects
				(font
					(size 1.016 1.016)
					(thickness 0.1524)
				)
			)
		)
		(duplicate_pad_numbers_are_jumpers no)
		(fp_rect
			(start -0.4318 0.9525)
			(end 0.4318 -0.9525)
			(stroke
				(width 0)
				(type default)
			)
			(fill no)
			(layer "F.CrtYd")
		)
		(fp_rect
			(start -0.4318 0.9525)
			(end 0.4318 -0.9525)
			(stroke
				(width 0)
				(type default)
			)
			(fill no)
			(layer "F.Fab")
		)
		(pad "1" smd custom
			(at 0 -0.4445 270)
			(size 0.1524 0.1524)
			(layers "F.Cu" "F.Mask" "F.Paste")
			(net "P12V_SW_R")
			(options
				(clearance outline)
				(anchor circle)
			)
			(primitives
				(gr_poly
					(pts
						(arc
							(start 0.3048 -0.2032)
							(mid 0.275042 -0.275042)
							(end 0.2032 -0.3048)
						)
						(arc
							(start -0.2032 -0.3048)
							(mid -0.275042 -0.275042)
							(end -0.3048 -0.2032)
						)
						(arc
							(start -0.3048 0.2032)
							(mid -0.275042 0.275042)
							(end -0.2032 0.3048)
						)
						(arc
							(start 0.2032 0.3048)
							(mid 0.275042 0.275042)
							(end 0.3048 0.2032)
						)
					)
					(width 0)
					(fill yes)
				)
			)
		)
		(pad "2" smd custom
			(at 0 0.4445 270)
			(size 0.1524 0.1524)
			(layers "F.Cu" "F.Mask" "F.Paste")
			(net "GND")
			(options
				(clearance outline)
				(anchor circle)
			)
			(primitives
				(gr_poly
					(pts
						(arc
							(start 0.3048 -0.2032)
							(mid 0.275042 -0.275042)
							(end 0.2032 -0.3048)
						)
						(arc
							(start -0.2032 -0.3048)
							(mid -0.275042 -0.275042)
							(end -0.3048 -0.2032)
						)
						(arc
							(start -0.3048 0.2032)
							(mid -0.275042 0.275042)
							(end -0.2032 0.3048)
						)
						(arc
							(start 0.2032 0.3048)
							(mid 0.275042 0.275042)
							(end 0.3048 0.2032)
						)
					)
					(width 0)
					(fill yes)
				)
			)
		)
	)
	(footprint ""
		(layer "F.Cu")
		(at 139.999974 -3.50012)
		(property "Reference" "H6"
			(at 0 0 0)
			(layer "F.SilkS")
			(hide yes)
			(effects
				(font
					(size 1.27 1.27)
				)
			)
		)
		(property "Value" "HOLET217B237R130-GP"
			(at -5.08 -0.4572 0)
			(unlocked yes)
			(layer "F.Fab")
			(hide yes)
			(effects
				(font
					(size 1.016 1.016)
					(thickness 0.1524)
				)
			)
		)
		(property "Device Type" "HOLET217B237R130"
			(at -5.08 -1.9812 0)
			(unlocked yes)
			(layer "F.Fab")
			(hide yes)
			(effects
				(font
					(size 1.016 1.016)
					(thickness 0.1524)
				)
			)
		)
		(duplicate_pad_numbers_are_jumpers no)
		(fp_poly
			(pts
				(arc
					(start 3.3147 0)
					(mid -3.3147 0)
					(end 3.3147 0)
				)
			)
			(stroke
				(width 0)
				(type default)
			)
			(fill no)
			(layer "B.CrtYd")
		)
		(fp_poly
			(pts
				(arc
					(start 3.0607 0)
					(mid -3.0607 0)
					(end 3.0607 0)
				)
			)
			(stroke
				(width 0)
				(type default)
			)
			(fill no)
			(layer "F.CrtYd")
		)
		(fp_poly
			(pts
				(arc
					(start 3.3147 0)
					(mid -3.3147 0)
					(end 3.3147 0)
				)
			)
			(stroke
				(width 0)
				(type default)
			)
			(fill no)
			(layer "B.Fab")
		)
		(fp_poly
			(pts
				(arc
					(start 3.0607 0)
					(mid -3.0607 0)
					(end 3.0607 0)
				)
			)
			(stroke
				(width 0)
				(type default)
			)
			(fill no)
			(layer "F.Fab")
		)
		(pad "1" thru_hole circle
			(at 0 0)
			(size 5.5118 5.5118)
			(drill 3.302)
			(layers "*.Cu" "*.Mask")
			(remove_unused_layers no)
			(net "GND")
			(clearance -0.5969)
			(thermal_gap 0.3048)
			(padstack
				(mode front_inner_back)
				(layer "Inner"
					(shape circle)
					(size 3.7084 3.7084)
					(clearance 0.3048)
				)
				(layer "B.Cu"
					(shape circle)
					(size 6.0198 6.0198)
					(clearance -0.8509)
				)
			)
		)
	)
	(footprint ""
		(layer "F.Cu")
		(at 60.694824 -8.457946 90)
		(property "Reference" "C22"
			(at 0 0 90)
			(layer "F.SilkS")
			(hide yes)
			(effects
				(font
					(size 1.27 1.27)
				)
			)
		)
		(property "Value" "SC10U25V6KX-1GP"
			(at -0.0762 -5.1308 90)
			(unlocked yes)
			(layer "F.Fab")
			(hide yes)
			(effects
				(font
					(size 1.016 1.016)
					(thickness 0.1524)
				)
			)
		)
		(property "Device Type" "C1206H71"
			(at -0.127 -6.6548 90)
			(unlocked yes)
			(layer "F.Fab")
			(hide yes)
			(effects
				(font
					(size 1.016 1.016)
					(thickness 0.1524)
				)
			)
		)
		(duplicate_pad_numbers_are_jumpers no)
		(fp_line
			(start 1.016 -2.2352)
			(end 1.016 -0.8382)
			(stroke
				(width 0.1524)
				(type default)
			)
			(layer "F.SilkS")
		)
		(fp_line
			(start -1.016 -2.2352)
			(end 1.016 -2.2352)
			(stroke
				(width 0.1524)
				(type default)
			)
			(layer "F.SilkS")
		)
		(fp_line
			(start -1.016 -0.8382)
			(end -1.016 -2.2352)
			(stroke
				(width 0.1524)
				(type default)
			)
			(layer "F.SilkS")
		)
		(fp_line
			(start 1.016 0.8382)
			(end 1.016 2.2352)
			(stroke
				(width 0.1524)
				(type default)
			)
			(layer "F.SilkS")
		)
		(fp_line
			(start 1.016 2.2352)
			(end -1.016 2.2352)
			(stroke
				(width 0.1524)
				(type default)
			)
			(layer "F.SilkS")
		)
		(fp_line
			(start -1.016 2.2352)
			(end -1.016 0.8382)
			(stroke
				(width 0.1524)
				(type default)
			)
			(layer "F.SilkS")
		)
		(fp_rect
			(start -1.0922 2.3114)
			(end 1.0922 -2.3114)
			(stroke
				(width 0)
				(type default)
			)
			(fill no)
			(layer "F.CrtYd")
		)
		(fp_poly
			(pts
				(xy 1.0922 -2.3114) (xy 1.0922 2.3114) (xy -1.0922 2.3114) (xy -1.0922 -2.3114)
			)
			(stroke
				(width 0)
				(type default)
			)
			(fill no)
			(layer "F.Fab")
		)
		(pad "1" smd rect
			(at 0 -1.397 90)
			(size 1.651 1.27)
			(layers "F.Cu" "F.Mask" "F.Paste")
			(net "P12V_SW_L")
		)
		(pad "2" smd rect
			(at 0 1.397 90)
			(size 1.651 1.27)
			(layers "F.Cu" "F.Mask" "F.Paste")
			(net "GND")
		)
	)
)
